(kicad_pcb
	(version 20260206)
	(generator "pcbnew")
	(generator_version "10.0")
	(general
		(thickness 1.6)
		(legacy_teardrops no)
	)
	(paper "A4")
	(title_block
		(title "03242023_DA0F0TMBIJ0_F0T_Motherboard_J_brd_V01_OCP.brd")
		(comment 1 "Grand Teton / footprints 3378-3383 of 6105")
	)
	(layers
		(0 "F.Cu" signal "TOP")
		(4 "In1.Cu" signal "GND")
		(6 "In2.Cu" signal "IN1")
		(8 "In3.Cu" signal "GND1")
		(10 "In4.Cu" signal "IN2")
		(12 "In5.Cu" signal "GND2")
		(14 "In6.Cu" signal "IN3")
		(16 "In7.Cu" signal "GND3")
		(18 "In8.Cu" signal "VCC")
		(20 "In9.Cu" signal "VCC1")
		(22 "In10.Cu" signal "GND4")
		(24 "In11.Cu" signal "IN4")
		(26 "In12.Cu" signal "GND5")
		(28 "In13.Cu" signal "IN5")
		(30 "In14.Cu" signal "GND6")
		(32 "In15.Cu" signal "IN6")
		(34 "In16.Cu" signal "GND7")
		(2 "B.Cu" signal "BOTTOM")
		(9 "F.Adhes" user "F.Adhesive")
		(11 "B.Adhes" user "B.Adhesive")
		(13 "F.Paste" user "Package Geometry/Pastemask Top")
		(15 "B.Paste" user "Package Geometry/Pastemask Bottom")
		(5 "F.SilkS" user "Ref Des/Silkscreen Top")
		(7 "B.SilkS" user "Ref Des/Silkscreen Bottom")
		(1 "F.Mask" user "Board Geometry/Soldermask Top")
		(3 "B.Mask" user "Board Geometry/Soldermask Bottom")
		(17 "Dwgs.User" user "User.Drawings")
		(19 "Cmts.User" user "User.Comments")
		(21 "Eco1.User" user "User.Eco1")
		(23 "Eco2.User" user "User.Eco2")
		(25 "Edge.Cuts" user "Board Geometry/Outline")
		(27 "Margin" user)
		(31 "F.CrtYd" user "Package Geometry/Place Bound Top")
		(29 "B.CrtYd" user "Package Geometry/Place Bound Bottom")
		(35 "F.Fab" user "Ref Des/Assembly Top")
		(33 "B.Fab" user "Ref Des/Assembly Bottom")
	)
	(footprint ""
		(layer "F.Cu")
		(at 326.647302 -20.548346 90)
		(property "Reference" "R1271"
			(at 0 0 90)
			(layer "F.SilkS")
			(hide yes)
			(effects
				(font
					(size 1.27 1.27)
				)
			)
		)
		(property "Value" ""
			(at 0 0 90)
			(layer "F.Fab")
			(effects
				(font
					(size 1.27 1.27)
				)
			)
		)
		(duplicate_pad_numbers_are_jumpers no)
		(fp_line
			(start 0.7874 -0.4064)
			(end 0.7874 0.4064)
			(stroke
				(width 0.1524)
				(type default)
			)
			(layer "F.SilkS")
		)
		(fp_line
			(start -0.7874 -0.4064)
			(end 0.7874 -0.4064)
			(stroke
				(width 0.1524)
				(type default)
			)
			(layer "F.SilkS")
		)
		(fp_line
			(start 0.7874 0.4064)
			(end -0.7874 0.4064)
			(stroke
				(width 0.1524)
				(type default)
			)
			(layer "F.SilkS")
		)
		(fp_line
			(start -0.7874 0.4064)
			(end -0.7874 -0.4064)
			(stroke
				(width 0.1524)
				(type default)
			)
			(layer "F.SilkS")
		)
		(fp_line
			(start -0.12065 -0.305054)
			(end -0.12065 -0.2794)
			(stroke
				(width 0.1)
				(type default)
			)
			(layer "F.Fab")
		)
		(fp_line
			(start -0.67945 -0.305054)
			(end -0.12065 -0.305054)
			(stroke
				(width 0.1)
				(type default)
			)
			(layer "F.Fab")
		)
		(fp_line
			(start 0.67945 -0.3048)
			(end 0.67945 0.3048)
			(stroke
				(width 0.1)
				(type default)
			)
			(layer "F.Fab")
		)
		(fp_line
			(start 0.12065 -0.3048)
			(end 0.67945 -0.3048)
			(stroke
				(width 0.1)
				(type default)
			)
			(layer "F.Fab")
		)
		(fp_line
			(start 0.12065 -0.2794)
			(end 0.12065 -0.3048)
			(stroke
				(width 0.1)
				(type default)
			)
			(layer "F.Fab")
		)
		(fp_line
			(start -0.12065 -0.2794)
			(end 0.12065 -0.2794)
			(stroke
				(width 0.1)
				(type default)
			)
			(layer "F.Fab")
		)
		(fp_line
			(start 0.120396 0.2794)
			(end -0.12065 0.2794)
			(stroke
				(width 0.1)
				(type default)
			)
			(layer "F.Fab")
		)
		(fp_line
			(start -0.12065 0.2794)
			(end -0.12065 0.3048)
			(stroke
				(width 0.1)
				(type default)
			)
			(layer "F.Fab")
		)
		(fp_line
			(start 0.67945 0.3048)
			(end 0.120396 0.3048)
			(stroke
				(width 0.1)
				(type default)
			)
			(layer "F.Fab")
		)
		(fp_line
			(start 0.120396 0.3048)
			(end 0.120396 0.2794)
			(stroke
				(width 0.1)
				(type default)
			)
			(layer "F.Fab")
		)
		(fp_line
			(start -0.12065 0.3048)
			(end -0.67945 0.3048)
			(stroke
				(width 0.1)
				(type default)
			)
			(layer "F.Fab")
		)
		(fp_line
			(start -0.67945 0.3048)
			(end -0.67945 -0.305054)
			(stroke
				(width 0.1)
				(type default)
			)
			(layer "F.Fab")
		)
		(pad "1" smd circle
			(at -0.40005 0 90)
			(size 0 0)
			(layers "F.Cu" "F.Mask" "F.Paste")
			(net "P3V3_AUX")
		)
		(pad "2" smd circle
			(at 0.40005 0 90)
			(size 0 0)
			(layers "F.Cu" "F.Mask" "F.Paste")
			(net "FM_PCH_SATA_RAID_KEY")
		)
	)
	(footprint ""
		(layer "F.Cu")
		(at 162.34283 -74.759058 180)
		(property "Reference" "R2315"
			(at 0 0 180)
			(layer "F.SilkS")
			(hide yes)
			(effects
				(font
					(size 1.27 1.27)
				)
			)
		)
		(property "Value" ""
			(at 0 0 180)
			(layer "F.Fab")
			(effects
				(font
					(size 1.27 1.27)
				)
			)
		)
		(duplicate_pad_numbers_are_jumpers no)
		(fp_line
			(start 0.7874 0.4064)
			(end -0.7874 0.4064)
			(stroke
				(width 0.1524)
				(type default)
			)
			(layer "F.SilkS")
		)
		(fp_line
			(start 0.7874 -0.4064)
			(end 0.7874 0.4064)
			(stroke
				(width 0.1524)
				(type default)
			)
			(layer "F.SilkS")
		)
		(fp_line
			(start -0.7874 0.4064)
			(end -0.7874 -0.4064)
			(stroke
				(width 0.1524)
				(type default)
			)
			(layer "F.SilkS")
		)
		(fp_line
			(start -0.7874 -0.4064)
			(end 0.7874 -0.4064)
			(stroke
				(width 0.1524)
				(type default)
			)
			(layer "F.SilkS")
		)
		(fp_line
			(start 0.67945 0.3048)
			(end 0.120396 0.3048)
			(stroke
				(width 0.1)
				(type default)
			)
			(layer "F.Fab")
		)
		(fp_line
			(start 0.67945 -0.3048)
			(end 0.67945 0.3048)
			(stroke
				(width 0.1)
				(type default)
			)
			(layer "F.Fab")
		)
		(fp_line
			(start 0.12065 -0.2794)
			(end 0.12065 -0.3048)
			(stroke
				(width 0.1)
				(type default)
			)
			(layer "F.Fab")
		)
		(fp_line
			(start 0.12065 -0.3048)
			(end 0.67945 -0.3048)
			(stroke
				(width 0.1)
				(type default)
			)
			(layer "F.Fab")
		)
		(fp_line
			(start 0.120396 0.3048)
			(end 0.120396 0.2794)
			(stroke
				(width 0.1)
				(type default)
			)
			(layer "F.Fab")
		)
		(fp_line
			(start 0.120396 0.2794)
			(end -0.12065 0.2794)
			(stroke
				(width 0.1)
				(type default)
			)
			(layer "F.Fab")
		)
		(fp_line
			(start -0.12065 0.3048)
			(end -0.67945 0.3048)
			(stroke
				(width 0.1)
				(type default)
			)
			(layer "F.Fab")
		)
		(fp_line
			(start -0.12065 0.2794)
			(end -0.12065 0.3048)
			(stroke
				(width 0.1)
				(type default)
			)
			(layer "F.Fab")
		)
		(fp_line
			(start -0.12065 -0.2794)
			(end 0.12065 -0.2794)
			(stroke
				(width 0.1)
				(type default)
			)
			(layer "F.Fab")
		)
		(fp_line
			(start -0.12065 -0.305054)
			(end -0.12065 -0.2794)
			(stroke
				(width 0.1)
				(type default)
			)
			(layer "F.Fab")
		)
		(fp_line
			(start -0.67945 0.3048)
			(end -0.67945 -0.305054)
			(stroke
				(width 0.1)
				(type default)
			)
			(layer "F.Fab")
		)
		(fp_line
			(start -0.67945 -0.305054)
			(end -0.12065 -0.305054)
			(stroke
				(width 0.1)
				(type default)
			)
			(layer "F.Fab")
		)
		(pad "1" smd circle
			(at -0.40005 0 180)
			(size 0 0)
			(layers "F.Cu" "F.Mask" "F.Paste")
			(net "P3V3_AUX")
		)
		(pad "2" smd circle
			(at 0.40005 0 180)
			(size 0 0)
			(layers "F.Cu" "F.Mask" "F.Paste")
			(net "PCA9543_S3M_INT0_N")
		)
	)
	(footprint ""
		(layer "F.Cu")
		(at 46.626018 -437.792368)
		(property "Reference" "R2990"
			(at 0 0 0)
			(layer "F.SilkS")
			(hide yes)
			(effects
				(font
					(size 1.27 1.27)
				)
			)
		)
		(property "Value" ""
			(at 0 0 0)
			(layer "F.Fab")
			(effects
				(font
					(size 1.27 1.27)
				)
			)
		)
		(duplicate_pad_numbers_are_jumpers no)
		(fp_line
			(start -0.7874 -0.4064)
			(end 0.7874 -0.4064)
			(stroke
				(width 0.1524)
				(type default)
			)
			(layer "F.SilkS")
		)
		(fp_line
			(start -0.7874 0.4064)
			(end -0.7874 -0.4064)
			(stroke
				(width 0.1524)
				(type default)
			)
			(layer "F.SilkS")
		)
		(fp_line
			(start 0.7874 -0.4064)
			(end 0.7874 0.4064)
			(stroke
				(width 0.1524)
				(type default)
			)
			(layer "F.SilkS")
		)
		(fp_line
			(start 0.7874 0.4064)
			(end -0.7874 0.4064)
			(stroke
				(width 0.1524)
				(type default)
			)
			(layer "F.SilkS")
		)
		(fp_line
			(start -0.67945 -0.305054)
			(end -0.12065 -0.305054)
			(stroke
				(width 0.1)
				(type default)
			)
			(layer "F.Fab")
		)
		(fp_line
			(start -0.67945 0.3048)
			(end -0.67945 -0.305054)
			(stroke
				(width 0.1)
				(type default)
			)
			(layer "F.Fab")
		)
		(fp_line
			(start -0.12065 -0.305054)
			(end -0.12065 -0.2794)
			(stroke
				(width 0.1)
				(type default)
			)
			(layer "F.Fab")
		)
		(fp_line
			(start -0.12065 -0.2794)
			(end 0.12065 -0.2794)
			(stroke
				(width 0.1)
				(type default)
			)
			(layer "F.Fab")
		)
		(fp_line
			(start -0.12065 0.2794)
			(end -0.12065 0.3048)
			(stroke
				(width 0.1)
				(type default)
			)
			(layer "F.Fab")
		)
		(fp_line
			(start -0.12065 0.3048)
			(end -0.67945 0.3048)
			(stroke
				(width 0.1)
				(type default)
			)
			(layer "F.Fab")
		)
		(fp_line
			(start 0.120396 0.2794)
			(end -0.12065 0.2794)
			(stroke
				(width 0.1)
				(type default)
			)
			(layer "F.Fab")
		)
		(fp_line
			(start 0.120396 0.3048)
			(end 0.120396 0.2794)
			(stroke
				(width 0.1)
				(type default)
			)
			(layer "F.Fab")
		)
		(fp_line
			(start 0.12065 -0.3048)
			(end 0.67945 -0.3048)
			(stroke
				(width 0.1)
				(type default)
			)
			(layer "F.Fab")
		)
		(fp_line
			(start 0.12065 -0.2794)
			(end 0.12065 -0.3048)
			(stroke
				(width 0.1)
				(type default)
			)
			(layer "F.Fab")
		)
		(fp_line
			(start 0.67945 -0.3048)
			(end 0.67945 0.3048)
			(stroke
				(width 0.1)
				(type default)
			)
			(layer "F.Fab")
		)
		(fp_line
			(start 0.67945 0.3048)
			(end 0.120396 0.3048)
			(stroke
				(width 0.1)
				(type default)
			)
			(layer "F.Fab")
		)
		(pad "1" smd circle
			(at -0.40005 0)
			(size 0 0)
			(layers "F.Cu" "F.Mask" "F.Paste")
			(net "SMB_2_BMC_GPU_BUF_R_SCL")
		)
		(pad "2" smd circle
			(at 0.40005 0)
			(size 0 0)
			(layers "F.Cu" "F.Mask" "F.Paste")
			(net "SMB_2_BMC_GPU_BUF_SCL")
		)
	)
	(footprint ""
		(layer "F.Cu")
		(at 113.494312 -129.408682 180)
		(property "Reference" "R3527"
			(at 0 0 180)
			(layer "F.SilkS")
			(hide yes)
			(effects
				(font
					(size 1.27 1.27)
				)
			)
		)
		(property "Value" ""
			(at 0 0 180)
			(layer "F.Fab")
			(effects
				(font
					(size 1.27 1.27)
				)
			)
		)
		(duplicate_pad_numbers_are_jumpers no)
		(fp_line
			(start 0.7874 0.4064)
			(end -0.7874 0.4064)
			(stroke
				(width 0.1524)
				(type default)
			)
			(layer "F.SilkS")
		)
		(fp_line
			(start 0.7874 -0.4064)
			(end 0.7874 0.4064)
			(stroke
				(width 0.1524)
				(type default)
			)
			(layer "F.SilkS")
		)
		(fp_line
			(start -0.7874 0.4064)
			(end -0.7874 -0.4064)
			(stroke
				(width 0.1524)
				(type default)
			)
			(layer "F.SilkS")
		)
		(fp_line
			(start -0.7874 -0.4064)
			(end 0.7874 -0.4064)
			(stroke
				(width 0.1524)
				(type default)
			)
			(layer "F.SilkS")
		)
		(fp_line
			(start 0.67945 0.3048)
			(end 0.120396 0.3048)
			(stroke
				(width 0.1)
				(type default)
			)
			(layer "F.Fab")
		)
		(fp_line
			(start 0.67945 -0.3048)
			(end 0.67945 0.3048)
			(stroke
				(width 0.1)
				(type default)
			)
			(layer "F.Fab")
		)
		(fp_line
			(start 0.12065 -0.2794)
			(end 0.12065 -0.3048)
			(stroke
				(width 0.1)
				(type default)
			)
			(layer "F.Fab")
		)
		(fp_line
			(start 0.12065 -0.3048)
			(end 0.67945 -0.3048)
			(stroke
				(width 0.1)
				(type default)
			)
			(layer "F.Fab")
		)
		(fp_line
			(start 0.120396 0.3048)
			(end 0.120396 0.2794)
			(stroke
				(width 0.1)
				(type default)
			)
			(layer "F.Fab")
		)
		(fp_line
			(start 0.120396 0.2794)
			(end -0.12065 0.2794)
			(stroke
				(width 0.1)
				(type default)
			)
			(layer "F.Fab")
		)
		(fp_line
			(start -0.12065 0.3048)
			(end -0.67945 0.3048)
			(stroke
				(width 0.1)
				(type default)
			)
			(layer "F.Fab")
		)
		(fp_line
			(start -0.12065 0.2794)
			(end -0.12065 0.3048)
			(stroke
				(width 0.1)
				(type default)
			)
			(layer "F.Fab")
		)
		(fp_line
			(start -0.12065 -0.2794)
			(end 0.12065 -0.2794)
			(stroke
				(width 0.1)
				(type default)
			)
			(layer "F.Fab")
		)
		(fp_line
			(start -0.12065 -0.305054)
			(end -0.12065 -0.2794)
			(stroke
				(width 0.1)
				(type default)
			)
			(layer "F.Fab")
		)
		(fp_line
			(start -0.67945 0.3048)
			(end -0.67945 -0.305054)
			(stroke
				(width 0.1)
				(type default)
			)
			(layer "F.Fab")
		)
		(fp_line
			(start -0.67945 -0.305054)
			(end -0.12065 -0.305054)
			(stroke
				(width 0.1)
				(type default)
			)
			(layer "F.Fab")
		)
		(pad "1" smd circle
			(at -0.40005 0 180)
			(size 0 0)
			(layers "F.Cu" "F.Mask" "F.Paste")
			(net "SMB_PCIE0_3V3AUX_SDA_R5")
		)
		(pad "2" smd circle
			(at 0.40005 0 180)
			(size 0 0)
			(layers "F.Cu" "F.Mask" "F.Paste")
			(net "SMB_SENSOR_E1S_3V3AUX_SDA")
		)
	)
	(footprint ""
		(layer "F.Cu")
		(at 367.411 -53.812948)
		(property "Reference" "R749"
			(at 0 0 0)
			(layer "F.SilkS")
			(hide yes)
			(effects
				(font
					(size 1.27 1.27)
				)
			)
		)
		(property "Value" ""
			(at 0 0 0)
			(layer "F.Fab")
			(effects
				(font
					(size 1.27 1.27)
				)
			)
		)
		(duplicate_pad_numbers_are_jumpers no)
		(fp_line
			(start -0.7874 -0.4064)
			(end 0.7874 -0.4064)
			(stroke
				(width 0.1524)
				(type default)
			)
			(layer "F.SilkS")
		)
		(fp_line
			(start -0.7874 0.4064)
			(end -0.7874 -0.4064)
			(stroke
				(width 0.1524)
				(type default)
			)
			(layer "F.SilkS")
		)
		(fp_line
			(start 0.7874 -0.4064)
			(end 0.7874 0.4064)
			(stroke
				(width 0.1524)
				(type default)
			)
			(layer "F.SilkS")
		)
		(fp_line
			(start 0.7874 0.4064)
			(end -0.7874 0.4064)
			(stroke
				(width 0.1524)
				(type default)
			)
			(layer "F.SilkS")
		)
		(fp_line
			(start -0.67945 -0.305054)
			(end -0.12065 -0.305054)
			(stroke
				(width 0.1)
				(type default)
			)
			(layer "F.Fab")
		)
		(fp_line
			(start -0.67945 0.3048)
			(end -0.67945 -0.305054)
			(stroke
				(width 0.1)
				(type default)
			)
			(layer "F.Fab")
		)
		(fp_line
			(start -0.12065 -0.305054)
			(end -0.12065 -0.2794)
			(stroke
				(width 0.1)
				(type default)
			)
			(layer "F.Fab")
		)
		(fp_line
			(start -0.12065 -0.2794)
			(end 0.12065 -0.2794)
			(stroke
				(width 0.1)
				(type default)
			)
			(layer "F.Fab")
		)
		(fp_line
			(start -0.12065 0.2794)
			(end -0.12065 0.3048)
			(stroke
				(width 0.1)
				(type default)
			)
			(layer "F.Fab")
		)
		(fp_line
			(start -0.12065 0.3048)
			(end -0.67945 0.3048)
			(stroke
				(width 0.1)
				(type default)
			)
			(layer "F.Fab")
		)
		(fp_line
			(start 0.120396 0.2794)
			(end -0.12065 0.2794)
			(stroke
				(width 0.1)
				(type default)
			)
			(layer "F.Fab")
		)
		(fp_line
			(start 0.120396 0.3048)
			(end 0.120396 0.2794)
			(stroke
				(width 0.1)
				(type default)
			)
			(layer "F.Fab")
		)
		(fp_line
			(start 0.12065 -0.3048)
			(end 0.67945 -0.3048)
			(stroke
				(width 0.1)
				(type default)
			)
			(layer "F.Fab")
		)
		(fp_line
			(start 0.12065 -0.2794)
			(end 0.12065 -0.3048)
			(stroke
				(width 0.1)
				(type default)
			)
			(layer "F.Fab")
		)
		(fp_line
			(start 0.67945 -0.3048)
			(end 0.67945 0.3048)
			(stroke
				(width 0.1)
				(type default)
			)
			(layer "F.Fab")
		)
		(fp_line
			(start 0.67945 0.3048)
			(end 0.120396 0.3048)
			(stroke
				(width 0.1)
				(type default)
			)
			(layer "F.Fab")
		)
		(pad "1" smd circle
			(at -0.40005 0)
			(size 0 0)
			(layers "F.Cu" "F.Mask" "F.Paste")
			(net "P1V05_PCH_AUX")
		)
		(pad "2" smd circle
			(at 0.40005 0)
			(size 0 0)
			(layers "F.Cu" "F.Mask" "F.Paste")
			(net "JTAG_DBP_TMS_PCH")
		)
	)
	(footprint ""
		(layer "F.Cu")
		(at 99.998276 -79.078836)
		(property "Reference" "D94"
			(at -50.01641 38.649402 90)
			(unlocked yes)
			(layer "F.SilkS")
			(effects
				(font
					(size 0.635 0.4064)
					(thickness 0.1524)
				)
				(justify left)
			)
		)
		(property "Value" ""
			(at 0 0 0)
			(layer "F.Fab")
			(effects
				(font
					(size 1.27 1.27)
				)
			)
		)
		(duplicate_pad_numbers_are_jumpers no)
		(fp_line
			(start -0.90678 0.4826)
			(end -0.90678 -0.4699)
			(stroke
				(width 0.1524)
				(type default)
			)
			(layer "F.SilkS")
		)
		(fp_line
			(start -0.89408 -0.4826)
			(end 0.90678 -0.4826)
			(stroke
				(width 0.1524)
				(type default)
			)
			(layer "F.SilkS")
		)
		(fp_line
			(start -0.79248 -0.4826)
			(end 1.03378 -0.4826)
			(stroke
				(width 0.1524)
				(type default)
			)
			(layer "F.SilkS")
		)
		(fp_line
			(start -0.64008 -0.4826)
			(end 1.16078 -0.4826)
			(stroke
				(width 0.1524)
				(type default)
			)
			(layer "F.SilkS")
		)
		(fp_line
			(start 0.90678 -0.4826)
			(end 0.90678 0.4826)
			(stroke
				(width 0.1524)
				(type default)
			)
			(layer "F.SilkS")
		)
		(fp_line
			(start 0.90678 0.4826)
			(end -0.90678 0.4826)
			(stroke
				(width 0.1524)
				(type default)
			)
			(layer "F.SilkS")
		)
		(fp_line
			(start 1.03378 -0.4826)
			(end 1.03378 0.4826)
			(stroke
				(width 0.1524)
				(type default)
			)
			(layer "F.SilkS")
		)
		(fp_line
			(start 1.03378 0.4826)
			(end -0.79248 0.4826)
			(stroke
				(width 0.1524)
				(type default)
			)
			(layer "F.SilkS")
		)
		(fp_line
			(start 1.16078 -0.4826)
			(end 1.16078 0.4826)
			(stroke
				(width 0.1524)
				(type default)
			)
			(layer "F.SilkS")
		)
		(fp_line
			(start 1.16078 0.4826)
			(end -0.64008 0.4826)
			(stroke
				(width 0.1524)
				(type default)
			)
			(layer "F.SilkS")
		)
		(fp_line
			(start -0.499872 -0.249936)
			(end 0.499872 -0.249936)
			(stroke
				(width 0.1)
				(type default)
			)
			(layer "F.Fab")
		)
		(fp_line
			(start -0.499872 0.249936)
			(end -0.499872 -0.249936)
			(stroke
				(width 0.1)
				(type default)
			)
			(layer "F.Fab")
		)
		(fp_line
			(start 0.499872 -0.249936)
			(end 0.499872 0.249936)
			(stroke
				(width 0.1)
				(type default)
			)
			(layer "F.Fab")
		)
		(fp_line
			(start 0.499872 0.249936)
			(end -0.499872 0.249936)
			(stroke
				(width 0.1)
				(type default)
			)
			(layer "F.Fab")
		)
		(pad "A" smd rect
			(at -0.47498 0)
			(size 0.6096 0.7112)
			(layers "F.Cu" "F.Mask" "F.Paste")
			(net "LED_FM_PCH_SLP_S4_N")
		)
		(pad "C" smd rect
			(at 0.47498 0)
			(size 0.6096 0.7112)
			(layers "F.Cu" "F.Mask" "F.Paste")
			(net "LED_FM_PCH_SLP_S4_N_D")
		)
	)
)
